(kicad_pcb
	(version 20260206)
	(generator "pcbnew")
	(generator_version "10.0")
	(general
		(thickness 1.6)
		(legacy_teardrops no)
	)
	(paper "A4")
	(title_block
		(title "Wiwynn_Tioga_Pass_MB.brd")
		(comment 1 "Tioga Pass / footprints 4391-4396 of 4770")
	)
	(layers
		(0 "F.Cu" signal "TOP")
		(4 "In1.Cu" signal "L2GND")
		(6 "In2.Cu" signal "L3")
		(8 "In3.Cu" signal "L4GND")
		(10 "In4.Cu" signal "L5")
		(12 "In5.Cu" signal "L6GND")
		(14 "In6.Cu" signal "L7VCC")
		(16 "In7.Cu" signal "L8VCC")
		(18 "In8.Cu" signal "L9GND")
		(20 "In9.Cu" signal "L10")
		(22 "In10.Cu" signal "L11GND")
		(24 "In11.Cu" signal "L12")
		(26 "In12.Cu" signal "L13GND")
		(2 "B.Cu" signal "BOTTOM")
		(9 "F.Adhes" user "F.Adhesive")
		(11 "B.Adhes" user "B.Adhesive")
		(13 "F.Paste" user "Package Geometry/Pastemask Top")
		(15 "B.Paste" user "Package Geometry/Pastemask Bottom")
		(5 "F.SilkS" user "Ref Des/Silkscreen Top")
		(7 "B.SilkS" user "Ref Des/Silkscreen Bottom")
		(1 "F.Mask" user "Board Geometry/Soldermask Top")
		(3 "B.Mask" user "Board Geometry/Soldermask Bottom")
		(17 "Dwgs.User" user "User.Drawings")
		(19 "Cmts.User" user "User.Comments")
		(21 "Eco1.User" user "User.Eco1")
		(23 "Eco2.User" user "User.Eco2")
		(25 "Edge.Cuts" user "Board Geometry/Outline")
		(27 "Margin" user)
		(31 "F.CrtYd" user "Package Geometry/Place Bound Top")
		(29 "B.CrtYd" user "Package Geometry/Place Bound Bottom")
		(35 "F.Fab" user "Ref Des/Assembly Top")
		(33 "B.Fab" user "Ref Des/Assembly Bottom")
	)
	(footprint ""
		(layer "B.Cu")
		(at 395.7828 -27.92476 90)
		(property "Reference" "U8F3"
			(at 0 0 90)
			(layer "B.SilkS")
			(hide yes)
			(effects
				(font
					(size 1.27 1.27)
				)
				(justify mirror)
			)
		)
		(property "Value" "*"
			(at 2.3622 -8.3185 90)
			(unlocked yes)
			(layer "B.Fab")
			(hide yes)
			(effects
				(font
					(size 1.27 1.016)
					(thickness 0.1524)
				)
				(justify mirror)
			)
		)
		(property "Device Type" "SN74LVC2G07DCKR-GP_DISCRET-G4-A"
			(at 2.3622 -10.2235 90)
			(unlocked yes)
			(layer "B.Fab")
			(hide yes)
			(effects
				(font
					(size 1.27 1.016)
					(thickness 0.1524)
				)
				(justify mirror)
			)
		)
		(duplicate_pad_numbers_are_jumpers no)
		(fp_line
			(start 1.4478 -1.7018)
			(end 1.4478 1.7018)
			(stroke
				(width 0.1524)
				(type default)
			)
			(layer "B.SilkS")
		)
		(fp_line
			(start -1.4478 -1.7018)
			(end 1.4478 -1.7018)
			(stroke
				(width 0.1524)
				(type default)
			)
			(layer "B.SilkS")
		)
		(fp_line
			(start 1.4478 1.7018)
			(end -1.4478 1.7018)
			(stroke
				(width 0.1524)
				(type default)
			)
			(layer "B.SilkS")
		)
		(fp_line
			(start -1.4478 1.7018)
			(end -1.4478 -1.7018)
			(stroke
				(width 0.1524)
				(type default)
			)
			(layer "B.SilkS")
		)
		(fp_line
			(start 1.5494 1.7907)
			(end 1.5494 0.8255)
			(stroke
				(width 0.635)
				(type default)
			)
			(layer "B.SilkS")
		)
		(fp_line
			(start 0.5715 1.7907)
			(end 1.5494 1.7907)
			(stroke
				(width 0.635)
				(type default)
			)
			(layer "B.SilkS")
		)
		(fp_poly
			(pts
				(xy 1.81864 2.02184) (xy 2.17424 1.66624) (xy 2.39268 1.4478) (xy 2.41808 1.4224) (xy 2.42824 1.4224)
				(xy 2.42824 1.4478) (xy 2.42824 2.6162) (xy 2.413 2.6162) (xy 2.17424 2.37744)
			)
			(stroke
				(width 0)
				(type default)
			)
			(fill yes)
			(layer "B.SilkS")
		)
		(fp_poly
			(pts
				(xy 1.524 -1.778) (xy -1.524 -1.778) (xy -1.524 1.778) (xy 1.524 1.778)
			)
			(stroke
				(width 0)
				(type default)
			)
			(fill no)
			(layer "B.CrtYd")
		)
		(fp_poly
			(pts
				(xy 1.524 -1.778) (xy -1.524 -1.778) (xy -1.524 1.778) (xy 1.524 1.778)
			)
			(stroke
				(width 0)
				(type default)
			)
			(fill no)
			(layer "B.Fab")
		)
		(pad "1" smd rect
			(at 0.65024 0.9398 270)
			(size 0.4064 1.016)
			(layers "B.Cu" "B.Mask" "B.Paste")
			(net "RST_BMC_SYSRST_BTN_OUT_N")
		)
		(pad "2" smd rect
			(at 0 0.9398 270)
			(size 0.4064 1.016)
			(layers "B.Cu" "B.Mask" "B.Paste")
			(net "GND")
		)
		(pad "3" smd rect
			(at -0.65024 0.9398 270)
			(size 0.4064 1.016)
			(layers "B.Cu" "B.Mask" "B.Paste")
			(net "FM_BMC_PWRBTN_OUT_N")
		)
		(pad "4" smd rect
			(at -0.65024 -0.9398 270)
			(size 0.4064 1.016)
			(layers "B.Cu" "B.Mask" "B.Paste")
			(net "FM_PCH_PWRBTN_R_N")
		)
		(pad "5" smd rect
			(at 0 -0.9398 270)
			(size 0.4064 1.016)
			(layers "B.Cu" "B.Mask" "B.Paste")
			(net "P3V3_STBY")
		)
		(pad "6" smd rect
			(at 0.65024 -0.9398 270)
			(size 0.4064 1.016)
			(layers "B.Cu" "B.Mask" "B.Paste")
			(net "RST_BMC_SYSRST_BTN_OUT_B_R_N")
		)
	)
	(footprint ""
		(layer "B.Cu")
		(at 282.259024 -71.867014 -90)
		(property "Reference" "R4P11"
			(at 0 0 90)
			(layer "B.SilkS")
			(hide yes)
			(effects
				(font
					(size 1.27 1.27)
				)
				(justify mirror)
			)
		)
		(property "Value" ""
			(at 0 0 90)
			(layer "B.Fab")
			(effects
				(font
					(size 1.27 1.27)
				)
				(justify mirror)
			)
		)
		(duplicate_pad_numbers_are_jumpers no)
		(fp_rect
			(start 0.2794 0.9906)
			(end -0.2794 -0.1016)
			(stroke
				(width 0)
				(type default)
			)
			(fill no)
			(layer "B.CrtYd")
		)
		(fp_line
			(start -0.2794 0.9906)
			(end -0.2794 -0.1016)
			(stroke
				(width 0.1)
				(type default)
			)
			(layer "B.Fab")
		)
		(fp_line
			(start 0.2794 0.9906)
			(end -0.2794 0.9906)
			(stroke
				(width 0.1)
				(type default)
			)
			(layer "B.Fab")
		)
		(fp_line
			(start -0.2794 -0.1016)
			(end 0.2794 -0.1016)
			(stroke
				(width 0.1)
				(type default)
			)
			(layer "B.Fab")
		)
		(fp_line
			(start 0.2794 -0.1016)
			(end 0.2794 0.9906)
			(stroke
				(width 0.1)
				(type default)
			)
			(layer "B.Fab")
		)
		(pad "1" smd rect
			(at 0 0 90)
			(size 0.508 0.508)
			(layers "B.Cu" "B.Mask" "B.Paste")
			(net "A_CPU0_ABC_RCOMP2")
		)
		(pad "2" smd rect
			(at 0 0.889 90)
			(size 0.508 0.508)
			(layers "B.Cu" "B.Mask" "B.Paste")
			(net "GND")
		)
		(zone
			(layer "B.Cu")
			(hatch none 0.5)
			(connect_pads
				(clearance 0)
			)
			(min_thickness 0.25)
			(keepout
				(tracks allowed)
				(vias not_allowed)
				(pads allowed)
				(copperpour not_allowed)
				(footprints allowed)
			)
			(placement
				(enabled no)
				(sheetname "")
			)
			(fill
				(thermal_gap 0.5)
				(thermal_bridge_width 0.5)
				(island_removal_mode 0)
			)
			(polygon
				(pts
					(xy 281.624024 -71.613014) (xy 282.005024 -71.613014) (xy 282.005024 -72.121014) (xy 281.624024 -72.121014)
				)
			)
		)
		(zone
			(layer "B.Cu")
			(hatch none 0.5)
			(connect_pads
				(clearance 0)
			)
			(min_thickness 0.25)
			(keepout
				(tracks not_allowed)
				(vias allowed)
				(pads allowed)
				(copperpour not_allowed)
				(footprints allowed)
			)
			(placement
				(enabled no)
				(sheetname "")
			)
			(fill
				(thermal_gap 0.5)
				(thermal_bridge_width 0.5)
				(island_removal_mode 0)
			)
			(polygon
				(pts
					(xy 281.624024 -71.613014) (xy 282.005024 -71.613014) (xy 282.005024 -72.121014) (xy 281.624024 -72.121014)
				)
			)
		)
	)
	(footprint ""
		(layer "B.Cu")
		(at 416.883596 -32.327342 180)
		(property "Reference" "C25W27"
			(at 0.8382 -0.67818 180)
			(unlocked yes)
			(layer "B.SilkS")
			(effects
				(font
					(size 0.4064 0.254)
					(thickness 0.1524)
				)
				(justify left mirror)
			)
		)
		(property "Value" ""
			(at 0 0 0)
			(layer "B.Fab")
			(effects
				(font
					(size 1.27 1.27)
				)
				(justify mirror)
			)
		)
		(duplicate_pad_numbers_are_jumpers no)
		(fp_poly
			(pts
				(xy -0.3048 -0.1016) (xy -0.3048 0.9906) (xy 0.3048 0.9906) (xy 0.3048 -0.1016)
			)
			(stroke
				(width 0)
				(type default)
			)
			(fill no)
			(layer "B.CrtYd")
		)
		(fp_line
			(start 0.3048 0.9906)
			(end -0.3048 0.9906)
			(stroke
				(width 0.1)
				(type default)
			)
			(layer "B.Fab")
		)
		(fp_line
			(start 0.3048 -0.1016)
			(end 0.3048 0.9906)
			(stroke
				(width 0.1)
				(type default)
			)
			(layer "B.Fab")
		)
		(fp_line
			(start -0.3048 0.9906)
			(end -0.3048 -0.1016)
			(stroke
				(width 0.1)
				(type default)
			)
			(layer "B.Fab")
		)
		(fp_line
			(start -0.3048 -0.1016)
			(end 0.3048 -0.1016)
			(stroke
				(width 0.1)
				(type default)
			)
			(layer "B.Fab")
		)
		(pad "1" smd rect
			(at 0 0)
			(size 0.508 0.508)
			(layers "B.Cu" "B.Mask" "B.Paste")
			(net "P1V15_AUX_BMC")
		)
		(pad "2" smd rect
			(at 0 0.889)
			(size 0.508 0.508)
			(layers "B.Cu" "B.Mask" "B.Paste")
			(net "GND")
		)
		(zone
			(layer "B.Cu")
			(hatch none 0.5)
			(connect_pads
				(clearance 0)
			)
			(min_thickness 0.25)
			(keepout
				(tracks not_allowed)
				(vias allowed)
				(pads allowed)
				(copperpour not_allowed)
				(footprints allowed)
			)
			(placement
				(enabled no)
				(sheetname "")
			)
			(fill
				(thermal_gap 0.5)
				(thermal_bridge_width 0.5)
				(island_removal_mode 0)
			)
			(polygon
				(pts
					(xy 416.629596 -32.962342) (xy 417.137596 -32.962342) (xy 417.137596 -32.581342) (xy 416.629596 -32.581342)
				)
			)
		)
		(zone
			(layer "B.Cu")
			(hatch none 0.5)
			(connect_pads
				(clearance 0)
			)
			(min_thickness 0.25)
			(keepout
				(tracks allowed)
				(vias not_allowed)
				(pads allowed)
				(copperpour not_allowed)
				(footprints allowed)
			)
			(placement
				(enabled no)
				(sheetname "")
			)
			(fill
				(thermal_gap 0.5)
				(thermal_bridge_width 0.5)
				(island_removal_mode 0)
			)
			(polygon
				(pts
					(xy 416.629596 -32.581342) (xy 417.137596 -32.581342) (xy 417.137596 -32.962342) (xy 416.629596 -32.962342)
				)
			)
		)
	)
	(footprint ""
		(layer "B.Cu")
		(at 168.61028 -148.7424 -90)
		(property "Reference" "R6L5"
			(at 0 0 90)
			(layer "B.SilkS")
			(hide yes)
			(effects
				(font
					(size 1.27 1.27)
				)
				(justify mirror)
			)
		)
		(property "Value" ""
			(at 0 0 90)
			(layer "B.Fab")
			(effects
				(font
					(size 1.27 1.27)
				)
				(justify mirror)
			)
		)
		(duplicate_pad_numbers_are_jumpers no)
		(fp_rect
			(start -0.2794 -0.1016)
			(end 0.2794 0.9906)
			(stroke
				(width 0)
				(type default)
			)
			(fill no)
			(layer "B.CrtYd")
		)
		(fp_line
			(start -0.2794 0.9906)
			(end -0.2794 -0.1016)
			(stroke
				(width 0.1)
				(type default)
			)
			(layer "B.Fab")
		)
		(fp_line
			(start 0.2794 0.9906)
			(end -0.2794 0.9906)
			(stroke
				(width 0.1)
				(type default)
			)
			(layer "B.Fab")
		)
		(fp_line
			(start -0.2794 -0.1016)
			(end 0.2794 -0.1016)
			(stroke
				(width 0.1)
				(type default)
			)
			(layer "B.Fab")
		)
		(fp_line
			(start 0.2794 -0.1016)
			(end 0.2794 0.9906)
			(stroke
				(width 0.1)
				(type default)
			)
			(layer "B.Fab")
		)
		(pad "1" smd rect
			(at 0 0 90)
			(size 0.508 0.508)
			(layers "B.Cu" "B.Mask" "B.Paste")
			(net "P3V3")
		)
		(pad "2" smd rect
			(at 0 0.889 90)
			(size 0.508 0.508)
			(layers "B.Cu" "B.Mask" "B.Paste")
			(net "FM_PVTT_KLM_EN_R")
		)
		(zone
			(layer "B.Cu")
			(hatch none 0.5)
			(connect_pads
				(clearance 0)
			)
			(min_thickness 0.25)
			(keepout
				(tracks not_allowed)
				(vias allowed)
				(pads allowed)
				(copperpour not_allowed)
				(footprints allowed)
			)
			(placement
				(enabled no)
				(sheetname "")
			)
			(fill
				(thermal_gap 0.5)
				(thermal_bridge_width 0.5)
				(island_removal_mode 0)
			)
			(polygon
				(pts
					(xy 168.35628 -148.9964) (xy 167.97528 -148.9964) (xy 167.97528 -148.4884) (xy 168.35628 -148.4884)
				)
			)
		)
		(zone
			(layer "B.Cu")
			(hatch none 0.5)
			(connect_pads
				(clearance 0)
			)
			(min_thickness 0.25)
			(keepout
				(tracks allowed)
				(vias not_allowed)
				(pads allowed)
				(copperpour not_allowed)
				(footprints allowed)
			)
			(placement
				(enabled no)
				(sheetname "")
			)
			(fill
				(thermal_gap 0.5)
				(thermal_bridge_width 0.5)
				(island_removal_mode 0)
			)
			(polygon
				(pts
					(xy 168.35628 -148.9964) (xy 167.97528 -148.9964) (xy 167.97528 -148.4884) (xy 168.35628 -148.4884)
				)
			)
		)
	)
	(footprint ""
		(layer "B.Cu")
		(at 418.719 -35.1155 180)
		(property "Reference" "C25W53"
			(at 0.8382 -0.67818 180)
			(unlocked yes)
			(layer "B.SilkS")
			(effects
				(font
					(size 0.4064 0.254)
					(thickness 0.1524)
				)
				(justify left mirror)
			)
		)
		(property "Value" ""
			(at 0 0 0)
			(layer "B.Fab")
			(effects
				(font
					(size 1.27 1.27)
				)
				(justify mirror)
			)
		)
		(duplicate_pad_numbers_are_jumpers no)
		(fp_poly
			(pts
				(xy -0.3048 -0.1016) (xy -0.3048 0.9906) (xy 0.3048 0.9906) (xy 0.3048 -0.1016)
			)
			(stroke
				(width 0)
				(type default)
			)
			(fill no)
			(layer "B.CrtYd")
		)
		(fp_line
			(start 0.3048 0.9906)
			(end -0.3048 0.9906)
			(stroke
				(width 0.1)
				(type default)
			)
			(layer "B.Fab")
		)
		(fp_line
			(start 0.3048 -0.1016)
			(end 0.3048 0.9906)
			(stroke
				(width 0.1)
				(type default)
			)
			(layer "B.Fab")
		)
		(fp_line
			(start -0.3048 0.9906)
			(end -0.3048 -0.1016)
			(stroke
				(width 0.1)
				(type default)
			)
			(layer "B.Fab")
		)
		(fp_line
			(start -0.3048 -0.1016)
			(end 0.3048 -0.1016)
			(stroke
				(width 0.1)
				(type default)
			)
			(layer "B.Fab")
		)
		(pad "1" smd rect
			(at 0 0)
			(size 0.508 0.508)
			(layers "B.Cu" "B.Mask" "B.Paste")
			(net "P1V2_AUX_BMC")
		)
		(pad "2" smd rect
			(at 0 0.889)
			(size 0.508 0.508)
			(layers "B.Cu" "B.Mask" "B.Paste")
			(net "GND")
		)
		(zone
			(layer "B.Cu")
			(hatch none 0.5)
			(connect_pads
				(clearance 0)
			)
			(min_thickness 0.25)
			(keepout
				(tracks not_allowed)
				(vias allowed)
				(pads allowed)
				(copperpour not_allowed)
				(footprints allowed)
			)
			(placement
				(enabled no)
				(sheetname "")
			)
			(fill
				(thermal_gap 0.5)
				(thermal_bridge_width 0.5)
				(island_removal_mode 0)
			)
			(polygon
				(pts
					(xy 418.465 -35.7505) (xy 418.973 -35.7505) (xy 418.973 -35.3695) (xy 418.465 -35.3695)
				)
			)
		)
		(zone
			(layer "B.Cu")
			(hatch none 0.5)
			(connect_pads
				(clearance 0)
			)
			(min_thickness 0.25)
			(keepout
				(tracks allowed)
				(vias not_allowed)
				(pads allowed)
				(copperpour not_allowed)
				(footprints allowed)
			)
			(placement
				(enabled no)
				(sheetname "")
			)
			(fill
				(thermal_gap 0.5)
				(thermal_bridge_width 0.5)
				(island_removal_mode 0)
			)
			(polygon
				(pts
					(xy 418.465 -35.3695) (xy 418.973 -35.3695) (xy 418.973 -35.7505) (xy 418.465 -35.7505)
				)
			)
		)
	)
	(footprint ""
		(layer "B.Cu")
		(at 409.884118 -87.526114 180)
		(property "Reference" "Q7E2"
			(at 1.20777 1.88214 90)
			(unlocked yes)
			(layer "B.SilkS")
			(effects
				(font
					(size 0.7874 0.5842)
					(thickness 0.1524)
				)
				(justify left mirror)
			)
		)
		(property "Value" ""
			(at 0 0 0)
			(layer "B.Fab")
			(effects
				(font
					(size 1.27 1.27)
				)
				(justify mirror)
			)
		)
		(duplicate_pad_numbers_are_jumpers no)
		(fp_circle
			(center 0.508 -0.7874)
			(end 0.381 -0.7874)
			(stroke
				(width 0.254)
				(type default)
			)
			(fill no)
			(layer "B.SilkS")
		)
		(fp_poly
			(pts
				(xy -0.2159 1.7526) (xy -1.5621 1.7526) (xy -1.5621 -0.4572) (xy -0.2159 -0.4572)
			)
			(stroke
				(width 0)
				(type default)
			)
			(fill no)
			(layer "B.CrtYd")
		)
		(fp_line
			(start -0.2159 1.75514)
			(end -1.5621 1.75514)
			(stroke
				(width 0.1)
				(type default)
			)
			(layer "B.Fab")
		)
		(fp_line
			(start -0.2159 -0.45466)
			(end -0.2159 1.75514)
			(stroke
				(width 0.1)
				(type default)
			)
			(layer "B.Fab")
		)
		(fp_line
			(start -1.5621 1.75514)
			(end -1.5621 -0.45466)
			(stroke
				(width 0.1)
				(type default)
			)
			(layer "B.Fab")
		)
		(fp_line
			(start -1.5621 -0.45466)
			(end -0.2159 -0.45466)
			(stroke
				(width 0.1)
				(type default)
			)
			(layer "B.Fab")
		)
		(fp_circle
			(center 0.508 -0.7874)
			(end 0.381 -0.7874)
			(stroke
				(width 0.254)
				(type default)
			)
			(fill no)
			(layer "B.Fab")
		)
		(pad "1" smd rect
			(at 0 0)
			(size 1.016 0.381)
			(layers "B.Cu" "B.Mask" "B.Paste")
			(net "GND")
		)
		(pad "2" smd rect
			(at 0 0.65024)
			(size 1.016 0.381)
			(layers "B.Cu" "B.Mask" "B.Paste")
			(net "IRQ_PVDDQ_GHJ_VRHOT_LVT3_N")
		)
		(pad "3" smd rect
			(at 0 1.30048)
			(size 1.016 0.381)
			(layers "B.Cu" "B.Mask" "B.Paste")
			(net "H_CPU1_MEMGHJ_MEMHOT_G_N")
		)
		(pad "4" smd rect
			(at -1.778 1.30048)
			(size 1.016 0.381)
			(layers "B.Cu" "B.Mask" "B.Paste")
			(net "GND")
		)
		(pad "5" smd rect
			(at -1.778 0.65024)
			(size 1.016 0.381)
			(layers "B.Cu" "B.Mask" "B.Paste")
			(net "H_CPU1_MEMGHJ_MEMHOT")
		)
		(pad "6" smd rect
			(at -1.778 0)
			(size 1.016 0.381)
			(layers "B.Cu" "B.Mask" "B.Paste")
			(net "H_CPU1_MEMGHJ_MEMHOT")
		)
		(zone
			(layer "B.Cu")
			(hatch none 0.5)
			(connect_pads
				(clearance 0)
			)
			(min_thickness 0.25)
			(keepout
				(tracks allowed)
				(vias not_allowed)
				(pads allowed)
				(copperpour not_allowed)
				(footprints allowed)
			)
			(placement
				(enabled no)
				(sheetname "")
			)
			(fill
				(thermal_gap 0.5)
				(thermal_bridge_width 0.5)
				(island_removal_mode 0)
			)
			(polygon
				(pts
					(xy 409.376118 -87.335614) (xy 410.392118 -87.335614) (xy 410.392118 -89.024714) (xy 409.376118 -89.024714)
				)
			)
		)
		(zone
			(layer "B.Cu")
			(hatch none 0.5)
			(connect_pads
				(clearance 0)
			)
			(min_thickness 0.25)
			(keepout
				(tracks allowed)
				(vias not_allowed)
				(pads allowed)
				(copperpour not_allowed)
				(footprints allowed)
			)
			(placement
				(enabled no)
				(sheetname "")
			)
			(fill
				(thermal_gap 0.5)
				(thermal_bridge_width 0.5)
				(island_removal_mode 0)
			)
			(polygon
				(pts
					(xy 411.154118 -87.335614) (xy 412.170118 -87.335614) (xy 412.170118 -89.024714) (xy 411.154118 -89.024714)
				)
			)
		)
	)
)
